(kicad_pcb
	(version 20260206)
	(generator "pcbnew")
	(generator_version "10.0")
	(general
		(thickness 1.6)
		(legacy_teardrops no)
	)
	(paper "A4")
	(title_block
		(title "01162023_DA0F0TEBIF0_F0T_Expander_BD_F_brd_V02_OCP.brd")
		(comment 1 "Grand Teton / footprints 87-92 of 9728")
	)
	(layers
		(0 "F.Cu" signal "TOP")
		(4 "In1.Cu" signal "GND")
		(6 "In2.Cu" signal "VCC")
		(8 "In3.Cu" signal "VCC1")
		(10 "In4.Cu" signal "GND1")
		(12 "In5.Cu" signal "IN1")
		(14 "In6.Cu" signal "GND2")
		(16 "In7.Cu" signal "IN2")
		(18 "In8.Cu" signal "GND3")
		(20 "In9.Cu" signal "IN3")
		(22 "In10.Cu" signal "GND4")
		(24 "In11.Cu" signal "IN4")
		(26 "In12.Cu" signal "GND5")
		(28 "In13.Cu" signal "IN5")
		(30 "In14.Cu" signal "GND6")
		(32 "In15.Cu" signal "IN6")
		(34 "In16.Cu" signal "GND7")
		(2 "B.Cu" signal "BOTTOM")
		(9 "F.Adhes" user "F.Adhesive")
		(11 "B.Adhes" user "B.Adhesive")
		(13 "F.Paste" user "Package Geometry/Pastemask Top")
		(15 "B.Paste" user "Package Geometry/Pastemask Bottom")
		(5 "F.SilkS" user "Ref Des/Silkscreen Top")
		(7 "B.SilkS" user "Ref Des/Silkscreen Bottom")
		(1 "F.Mask" user "Board Geometry/Soldermask Top")
		(3 "B.Mask" user "Board Geometry/Soldermask Bottom")
		(17 "Dwgs.User" user "User.Drawings")
		(19 "Cmts.User" user "User.Comments")
		(21 "Eco1.User" user "User.Eco1")
		(23 "Eco2.User" user "User.Eco2")
		(25 "Edge.Cuts" user "Board Geometry/Outline")
		(27 "Margin" user)
		(31 "F.CrtYd" user "Package Geometry/Place Bound Top")
		(29 "B.CrtYd" user "Package Geometry/Place Bound Bottom")
		(35 "F.Fab" user "Ref Des/Assembly Top")
		(33 "B.Fab" user "Ref Des/Assembly Bottom")
	)
	(footprint ""
		(layer "F.Cu")
		(at 278.374856 -48.753014 180)
		(property "Reference" "C330"
			(at 0 0 180)
			(layer "F.SilkS")
			(hide yes)
			(effects
				(font
					(size 1.27 1.27)
				)
			)
		)
		(property "Value" ""
			(at 0 0 180)
			(layer "F.Fab")
			(effects
				(font
					(size 1.27 1.27)
				)
			)
		)
		(duplicate_pad_numbers_are_jumpers no)
		(fp_line
			(start 0.7874 0.4064)
			(end -0.7874 0.4064)
			(stroke
				(width 0.1524)
				(type default)
			)
			(layer "F.SilkS")
		)
		(fp_line
			(start 0.7874 -0.4064)
			(end 0.7874 0.4064)
			(stroke
				(width 0.1524)
				(type default)
			)
			(layer "F.SilkS")
		)
		(fp_line
			(start -0.7874 0.4064)
			(end -0.7874 -0.4064)
			(stroke
				(width 0.1524)
				(type default)
			)
			(layer "F.SilkS")
		)
		(fp_line
			(start -0.7874 -0.4064)
			(end 0.7874 -0.4064)
			(stroke
				(width 0.1524)
				(type default)
			)
			(layer "F.SilkS")
		)
		(fp_line
			(start 0.67945 0.3048)
			(end 0.120396 0.3048)
			(stroke
				(width 0.1)
				(type default)
			)
			(layer "F.Fab")
		)
		(fp_line
			(start 0.67945 -0.3048)
			(end 0.67945 0.3048)
			(stroke
				(width 0.1)
				(type default)
			)
			(layer "F.Fab")
		)
		(fp_line
			(start 0.12065 -0.2794)
			(end 0.12065 -0.3048)
			(stroke
				(width 0.1)
				(type default)
			)
			(layer "F.Fab")
		)
		(fp_line
			(start 0.12065 -0.3048)
			(end 0.67945 -0.3048)
			(stroke
				(width 0.1)
				(type default)
			)
			(layer "F.Fab")
		)
		(fp_line
			(start 0.120396 0.3048)
			(end 0.120396 0.2794)
			(stroke
				(width 0.1)
				(type default)
			)
			(layer "F.Fab")
		)
		(fp_line
			(start 0.120396 0.2794)
			(end -0.12065 0.2794)
			(stroke
				(width 0.1)
				(type default)
			)
			(layer "F.Fab")
		)
		(fp_line
			(start -0.12065 0.3048)
			(end -0.67945 0.3048)
			(stroke
				(width 0.1)
				(type default)
			)
			(layer "F.Fab")
		)
		(fp_line
			(start -0.12065 0.2794)
			(end -0.12065 0.3048)
			(stroke
				(width 0.1)
				(type default)
			)
			(layer "F.Fab")
		)
		(fp_line
			(start -0.12065 -0.2794)
			(end 0.12065 -0.2794)
			(stroke
				(width 0.1)
				(type default)
			)
			(layer "F.Fab")
		)
		(fp_line
			(start -0.12065 -0.305054)
			(end -0.12065 -0.2794)
			(stroke
				(width 0.1)
				(type default)
			)
			(layer "F.Fab")
		)
		(fp_line
			(start -0.67945 0.3048)
			(end -0.67945 -0.305054)
			(stroke
				(width 0.1)
				(type default)
			)
			(layer "F.Fab")
		)
		(fp_line
			(start -0.67945 -0.305054)
			(end -0.12065 -0.305054)
			(stroke
				(width 0.1)
				(type default)
			)
			(layer "F.Fab")
		)
		(pad "1" smd circle
			(at -0.40005 0 180)
			(size 0 0)
			(layers "F.Cu" "F.Mask" "F.Paste")
			(net "P3V3_AUX")
		)
		(pad "2" smd circle
			(at 0.40005 0 180)
			(size 0 0)
			(layers "F.Cu" "F.Mask" "F.Paste")
			(net "GND")
		)
	)
	(footprint ""
		(layer "F.Cu")
		(at 222.690944 -98.36912 90)
		(property "Reference" "R859"
			(at 0 0 90)
			(layer "F.SilkS")
			(hide yes)
			(effects
				(font
					(size 1.27 1.27)
				)
			)
		)
		(property "Value" ""
			(at 0 0 90)
			(layer "F.Fab")
			(effects
				(font
					(size 1.27 1.27)
				)
			)
		)
		(duplicate_pad_numbers_are_jumpers no)
		(fp_line
			(start 0.7874 -0.4064)
			(end 0.7874 0.4064)
			(stroke
				(width 0.1524)
				(type default)
			)
			(layer "F.SilkS")
		)
		(fp_line
			(start -0.7874 -0.4064)
			(end 0.7874 -0.4064)
			(stroke
				(width 0.1524)
				(type default)
			)
			(layer "F.SilkS")
		)
		(fp_line
			(start 0.7874 0.4064)
			(end -0.7874 0.4064)
			(stroke
				(width 0.1524)
				(type default)
			)
			(layer "F.SilkS")
		)
		(fp_line
			(start -0.7874 0.4064)
			(end -0.7874 -0.4064)
			(stroke
				(width 0.1524)
				(type default)
			)
			(layer "F.SilkS")
		)
		(fp_line
			(start -0.12065 -0.305054)
			(end -0.12065 -0.2794)
			(stroke
				(width 0.1)
				(type default)
			)
			(layer "F.Fab")
		)
		(fp_line
			(start -0.67945 -0.305054)
			(end -0.12065 -0.305054)
			(stroke
				(width 0.1)
				(type default)
			)
			(layer "F.Fab")
		)
		(fp_line
			(start 0.67945 -0.3048)
			(end 0.67945 0.3048)
			(stroke
				(width 0.1)
				(type default)
			)
			(layer "F.Fab")
		)
		(fp_line
			(start 0.12065 -0.3048)
			(end 0.67945 -0.3048)
			(stroke
				(width 0.1)
				(type default)
			)
			(layer "F.Fab")
		)
		(fp_line
			(start 0.12065 -0.2794)
			(end 0.12065 -0.3048)
			(stroke
				(width 0.1)
				(type default)
			)
			(layer "F.Fab")
		)
		(fp_line
			(start -0.12065 -0.2794)
			(end 0.12065 -0.2794)
			(stroke
				(width 0.1)
				(type default)
			)
			(layer "F.Fab")
		)
		(fp_line
			(start 0.120396 0.2794)
			(end -0.12065 0.2794)
			(stroke
				(width 0.1)
				(type default)
			)
			(layer "F.Fab")
		)
		(fp_line
			(start -0.12065 0.2794)
			(end -0.12065 0.3048)
			(stroke
				(width 0.1)
				(type default)
			)
			(layer "F.Fab")
		)
		(fp_line
			(start 0.67945 0.3048)
			(end 0.120396 0.3048)
			(stroke
				(width 0.1)
				(type default)
			)
			(layer "F.Fab")
		)
		(fp_line
			(start 0.120396 0.3048)
			(end 0.120396 0.2794)
			(stroke
				(width 0.1)
				(type default)
			)
			(layer "F.Fab")
		)
		(fp_line
			(start -0.12065 0.3048)
			(end -0.67945 0.3048)
			(stroke
				(width 0.1)
				(type default)
			)
			(layer "F.Fab")
		)
		(fp_line
			(start -0.67945 0.3048)
			(end -0.67945 -0.305054)
			(stroke
				(width 0.1)
				(type default)
			)
			(layer "F.Fab")
		)
		(pad "1" smd circle
			(at -0.40005 0 90)
			(size 0 0)
			(layers "F.Cu" "F.Mask" "F.Paste")
			(net "P3V3_AUX")
		)
		(pad "2" smd circle
			(at 0.40005 0 90)
			(size 0 0)
			(layers "F.Cu" "F.Mask" "F.Paste")
			(net "PWRGD_P12V_NIC3")
		)
	)
	(footprint ""
		(layer "F.Cu")
		(at 248.421144 18.028412 180)
		(property "Reference" "DE01F_1"
			(at 2.472944 3.371342 0)
			(unlocked yes)
			(layer "F.SilkS")
			(effects
				(font
					(size 0.7874 0.5842)
					(thickness 0.1524)
				)
				(justify left)
			)
		)
		(property "Value" ""
			(at 0 0 180)
			(layer "F.Fab")
			(effects
				(font
					(size 1.27 1.27)
				)
			)
		)
		(duplicate_pad_numbers_are_jumpers no)
		(fp_line
			(start 1.2192 2.1082)
			(end -1.2192 2.1082)
			(stroke
				(width 0.1524)
				(type default)
			)
			(layer "F.SilkS")
		)
		(fp_line
			(start 1.2192 -2.1082)
			(end 1.2192 2.1082)
			(stroke
				(width 0.1524)
				(type default)
			)
			(layer "F.SilkS")
		)
		(fp_line
			(start -1.2192 2.1082)
			(end -1.2192 -2.1082)
			(stroke
				(width 0.1524)
				(type default)
			)
			(layer "F.SilkS")
		)
		(fp_line
			(start -1.2192 -2.1082)
			(end 1.2192 -2.1082)
			(stroke
				(width 0.1524)
				(type default)
			)
			(layer "F.SilkS")
		)
		(pad "" np_thru_hole circle
			(at -2.8829 -1.27 90)
			(size 1.0414 1.0414)
			(drill 1.0414)
			(layers "*.Cu" "*.Mask")
			(clearance 0.381)
			(thermal_gap 0.381)
		)
		(pad "" np_thru_hole circle
			(at -2.8829 1.27 90)
			(size 1.0414 1.0414)
			(drill 1.0414)
			(layers "*.Cu" "*.Mask")
			(clearance 0.381)
			(thermal_gap 0.381)
		)
		(pad "" np_thru_hole circle
			(at 3.4671 -1.27 90)
			(size 1.0414 1.0414)
			(drill 1.0414)
			(layers "*.Cu" "*.Mask")
			(clearance 0.381)
			(thermal_gap 0.381)
		)
		(pad "" np_thru_hole circle
			(at 3.4671 1.27 90)
			(size 1.0414 1.0414)
			(drill 1.0414)
			(layers "*.Cu" "*.Mask")
			(clearance 0.381)
			(thermal_gap 0.381)
		)
		(pad "1" smd rect
			(at 0.8255 -0.249936 90)
			(size 0.3048 0.508)
			(layers "F.Cu" "F.Mask" "F.Paste")
			(net "85_5INCH_TOP_DP")
		)
		(pad "2" smd rect
			(at 0.8255 0.249936 90)
			(size 0.3048 0.508)
			(layers "F.Cu" "F.Mask" "F.Paste")
			(net "85_5INCH_TOP_DN")
		)
		(pad "3" smd circle
			(at 0 0 180)
			(size 0 0)
			(layers "F.Cu" "F.Mask" "F.Paste")
			(net "COUPON_GND2")
		)
		(zone
			(layer "F.Cu")
			(hatch none 0.5)
			(connect_pads
				(clearance 0)
			)
			(min_thickness 0.25)
			(keepout
				(tracks not_allowed)
				(vias allowed)
				(pads allowed)
				(copperpour not_allowed)
				(footprints allowed)
			)
			(placement
				(enabled no)
				(sheetname "")
			)
			(fill
				(thermal_gap 0.5)
				(thermal_bridge_width 0.5)
				(island_removal_mode 0)
			)
			(polygon
				(pts
					(xy 247.303544 18.577052) (xy 247.303544 18.481548) (xy 247.900444 18.481548) (xy 247.900444 18.075148)
					(xy 247.303544 18.075148) (xy 247.303544 17.981676) (xy 247.900444 17.981676) (xy 247.900444 17.575276)
					(xy 247.303544 17.575276) (xy 247.303544 17.479772) (xy 248.002044 17.479772) (xy 248.002044 18.577052)
				)
			)
		)
		(zone
			(layers "F.Cu" "B.Cu" "In1.Cu" "In2.Cu" "In3.Cu" "In4.Cu" "In5.Cu" "In6.Cu"
				"In7.Cu" "In8.Cu" "In9.Cu" "In10.Cu" "In11.Cu" "In12.Cu" "In13.Cu" "In14.Cu"
				"In15.Cu" "In16.Cu"
			)
			(hatch none 0.5)
			(connect_pads
				(clearance 0)
			)
			(min_thickness 0.25)
			(keepout
				(tracks not_allowed)
				(vias allowed)
				(pads allowed)
				(copperpour not_allowed)
				(footprints allowed)
			)
			(placement
				(enabled no)
				(sheetname "")
			)
			(fill
				(thermal_gap 0.5)
				(thermal_bridge_width 0.5)
				(island_removal_mode 0)
			)
			(polygon
				(pts
					(arc
						(start 245.881144 16.758412)
						(mid 244.026944 16.758412)
						(end 245.881144 16.758412)
					)
				)
			)
		)
		(zone
			(layers "F.Cu" "B.Cu" "In1.Cu" "In2.Cu" "In3.Cu" "In4.Cu" "In5.Cu" "In6.Cu"
				"In7.Cu" "In8.Cu" "In9.Cu" "In10.Cu" "In11.Cu" "In12.Cu" "In13.Cu" "In14.Cu"
				"In15.Cu" "In16.Cu"
			)
			(hatch none 0.5)
			(connect_pads
				(clearance 0)
			)
			(min_thickness 0.25)
			(keepout
				(tracks not_allowed)
				(vias allowed)
				(pads allowed)
				(copperpour not_allowed)
				(footprints allowed)
			)
			(placement
				(enabled no)
				(sheetname "")
			)
			(fill
				(thermal_gap 0.5)
				(thermal_bridge_width 0.5)
				(island_removal_mode 0)
			)
			(polygon
				(pts
					(arc
						(start 245.881144 19.298412)
						(mid 244.026944 19.298412)
						(end 245.881144 19.298412)
					)
				)
			)
		)
		(zone
			(layers "F.Cu" "B.Cu" "In1.Cu" "In2.Cu" "In3.Cu" "In4.Cu" "In5.Cu" "In6.Cu"
				"In7.Cu" "In8.Cu" "In9.Cu" "In10.Cu" "In11.Cu" "In12.Cu" "In13.Cu" "In14.Cu"
				"In15.Cu" "In16.Cu"
			)
			(hatch none 0.5)
			(connect_pads
				(clearance 0)
			)
			(min_thickness 0.25)
			(keepout
				(tracks not_allowed)
				(vias allowed)
				(pads allowed)
				(copperpour not_allowed)
				(footprints allowed)
			)
			(placement
				(enabled no)
				(sheetname "")
			)
			(fill
				(thermal_gap 0.5)
				(thermal_bridge_width 0.5)
				(island_removal_mode 0)
			)
			(polygon
				(pts
					(arc
						(start 252.231144 16.758412)
						(mid 250.376944 16.758412)
						(end 252.231144 16.758412)
					)
				)
			)
		)
		(zone
			(layers "F.Cu" "B.Cu" "In1.Cu" "In2.Cu" "In3.Cu" "In4.Cu" "In5.Cu" "In6.Cu"
				"In7.Cu" "In8.Cu" "In9.Cu" "In10.Cu" "In11.Cu" "In12.Cu" "In13.Cu" "In14.Cu"
				"In15.Cu" "In16.Cu"
			)
			(hatch none 0.5)
			(connect_pads
				(clearance 0)
			)
			(min_thickness 0.25)
			(keepout
				(tracks not_allowed)
				(vias allowed)
				(pads allowed)
				(copperpour not_allowed)
				(footprints allowed)
			)
			(placement
				(enabled no)
				(sheetname "")
			)
			(fill
				(thermal_gap 0.5)
				(thermal_bridge_width 0.5)
				(island_removal_mode 0)
			)
			(polygon
				(pts
					(arc
						(start 252.231144 19.298412)
						(mid 250.376944 19.298412)
						(end 252.231144 19.298412)
					)
				)
			)
		)
	)
	(footprint ""
		(layer "F.Cu")
		(at 283.59862 -180.372766 180)
		(property "Reference" "R254"
			(at 0 0 180)
			(layer "F.SilkS")
			(hide yes)
			(effects
				(font
					(size 1.27 1.27)
				)
			)
		)
		(property "Value" ""
			(at 0 0 180)
			(layer "F.Fab")
			(effects
				(font
					(size 1.27 1.27)
				)
			)
		)
		(duplicate_pad_numbers_are_jumpers no)
		(fp_line
			(start 0.7874 0.4064)
			(end -0.7874 0.4064)
			(stroke
				(width 0.1524)
				(type default)
			)
			(layer "F.SilkS")
		)
		(fp_line
			(start 0.7874 -0.4064)
			(end 0.7874 0.4064)
			(stroke
				(width 0.1524)
				(type default)
			)
			(layer "F.SilkS")
		)
		(fp_line
			(start -0.7874 0.4064)
			(end -0.7874 -0.4064)
			(stroke
				(width 0.1524)
				(type default)
			)
			(layer "F.SilkS")
		)
		(fp_line
			(start -0.7874 -0.4064)
			(end 0.7874 -0.4064)
			(stroke
				(width 0.1524)
				(type default)
			)
			(layer "F.SilkS")
		)
		(fp_line
			(start 0.67945 0.3048)
			(end 0.120396 0.3048)
			(stroke
				(width 0.1)
				(type default)
			)
			(layer "F.Fab")
		)
		(fp_line
			(start 0.67945 -0.3048)
			(end 0.67945 0.3048)
			(stroke
				(width 0.1)
				(type default)
			)
			(layer "F.Fab")
		)
		(fp_line
			(start 0.12065 -0.2794)
			(end 0.12065 -0.3048)
			(stroke
				(width 0.1)
				(type default)
			)
			(layer "F.Fab")
		)
		(fp_line
			(start 0.12065 -0.3048)
			(end 0.67945 -0.3048)
			(stroke
				(width 0.1)
				(type default)
			)
			(layer "F.Fab")
		)
		(fp_line
			(start 0.120396 0.3048)
			(end 0.120396 0.2794)
			(stroke
				(width 0.1)
				(type default)
			)
			(layer "F.Fab")
		)
		(fp_line
			(start 0.120396 0.2794)
			(end -0.12065 0.2794)
			(stroke
				(width 0.1)
				(type default)
			)
			(layer "F.Fab")
		)
		(fp_line
			(start -0.12065 0.3048)
			(end -0.67945 0.3048)
			(stroke
				(width 0.1)
				(type default)
			)
			(layer "F.Fab")
		)
		(fp_line
			(start -0.12065 0.2794)
			(end -0.12065 0.3048)
			(stroke
				(width 0.1)
				(type default)
			)
			(layer "F.Fab")
		)
		(fp_line
			(start -0.12065 -0.2794)
			(end 0.12065 -0.2794)
			(stroke
				(width 0.1)
				(type default)
			)
			(layer "F.Fab")
		)
		(fp_line
			(start -0.12065 -0.305054)
			(end -0.12065 -0.2794)
			(stroke
				(width 0.1)
				(type default)
			)
			(layer "F.Fab")
		)
		(fp_line
			(start -0.67945 0.3048)
			(end -0.67945 -0.305054)
			(stroke
				(width 0.1)
				(type default)
			)
			(layer "F.Fab")
		)
		(fp_line
			(start -0.67945 -0.305054)
			(end -0.12065 -0.305054)
			(stroke
				(width 0.1)
				(type default)
			)
			(layer "F.Fab")
		)
		(pad "1" smd circle
			(at -0.40005 0 180)
			(size 0 0)
			(layers "F.Cu" "F.Mask" "F.Paste")
			(net "P3V3_AUX")
		)
		(pad "2" smd circle
			(at 0.40005 0 180)
			(size 0 0)
			(layers "F.Cu" "F.Mask" "F.Paste")
			(net "HP_NIC4_HSC_PWRGD_N")
		)
	)
	(footprint ""
		(layer "F.Cu")
		(at 292.743382 -350.098614 90)
		(property "Reference" "C589"
			(at 0 0 90)
			(layer "F.SilkS")
			(hide yes)
			(effects
				(font
					(size 1.27 1.27)
				)
			)
		)
		(property "Value" ""
			(at 0 0 90)
			(layer "F.Fab")
			(effects
				(font
					(size 1.27 1.27)
				)
			)
		)
		(duplicate_pad_numbers_are_jumpers no)
		(fp_line
			(start 0.299974 -0.150114)
			(end 0.299974 0.150114)
			(stroke
				(width 0.1)
				(type default)
			)
			(layer "F.Fab")
		)
		(fp_line
			(start -0.299974 -0.150114)
			(end 0.299974 -0.150114)
			(stroke
				(width 0.1)
				(type default)
			)
			(layer "F.Fab")
		)
		(fp_line
			(start 0.299974 0.150114)
			(end -0.299974 0.150114)
			(stroke
				(width 0.1)
				(type default)
			)
			(layer "F.Fab")
		)
		(fp_line
			(start -0.299974 0.150114)
			(end -0.299974 -0.150114)
			(stroke
				(width 0.1)
				(type default)
			)
			(layer "F.Fab")
		)
		(pad "1" smd rect
			(at -0.2667 0 90)
			(size 0.3048 0.381)
			(layers "F.Cu" "F.Mask" "F.Paste")
			(net "P5E_PEX2_STN7_TX_DP<124>")
		)
		(pad "2" smd rect
			(at 0.2667 0 90)
			(size 0.3048 0.381)
			(layers "F.Cu" "F.Mask" "F.Paste")
			(net "P5E_PEX2_STN7_TX_C_DP<124>")
		)
	)
	(footprint ""
		(layer "F.Cu")
		(at 123.415044 -20.72513)
		(property "Reference" "H102"
			(at -2.337054 -1.98628 0)
			(unlocked yes)
			(layer "B.SilkS")
			(effects
				(font
					(size 0.7874 0.5842)
					(thickness 0.1524)
				)
				(justify left mirror)
			)
		)
		(property "Value" ""
			(at 0 0 0)
			(layer "F.Fab")
			(effects
				(font
					(size 1.27 1.27)
				)
			)
		)
		(duplicate_pad_numbers_are_jumpers no)
		(pad "1" thru_hole rect
			(at 0 0)
			(size 4.2164 5.0038)
			(drill 2.0066
				(offset 0.099822 0)
			)
			(layers "*.Cu" "*.Mask")
			(remove_unused_layers no)
			(net "Net_8561")
			(clearance -0.8509)
			(padstack
				(mode front_inner_back)
				(layer "Inner"
					(shape circle)
					(size 4.0132 4.0132)
					(clearance -0.7493)
				)
				(layer "B.Cu"
					(shape circle)
					(size 4.0132 4.0132)
					(clearance -0.7493)
				)
			)
		)
	)
)
